(kicad_pcb
	(version 20260206)
	(generator "pcbnew")
	(generator_version "10.0")
	(general
		(thickness 1.6)
		(legacy_teardrops no)
	)
	(paper "A4")
	(title_block
		(title "03242023_DA0F0TMBIJ0_F0T_Motherboard_J_brd_V01_OCP.brd")
		(comment 1 "Grand Teton / footprints 6099-6104 of 6105")
	)
	(layers
		(0 "F.Cu" signal "TOP")
		(4 "In1.Cu" signal "GND")
		(6 "In2.Cu" signal "IN1")
		(8 "In3.Cu" signal "GND1")
		(10 "In4.Cu" signal "IN2")
		(12 "In5.Cu" signal "GND2")
		(14 "In6.Cu" signal "IN3")
		(16 "In7.Cu" signal "GND3")
		(18 "In8.Cu" signal "VCC")
		(20 "In9.Cu" signal "VCC1")
		(22 "In10.Cu" signal "GND4")
		(24 "In11.Cu" signal "IN4")
		(26 "In12.Cu" signal "GND5")
		(28 "In13.Cu" signal "IN5")
		(30 "In14.Cu" signal "GND6")
		(32 "In15.Cu" signal "IN6")
		(34 "In16.Cu" signal "GND7")
		(2 "B.Cu" signal "BOTTOM")
		(9 "F.Adhes" user "F.Adhesive")
		(11 "B.Adhes" user "B.Adhesive")
		(13 "F.Paste" user "Package Geometry/Pastemask Top")
		(15 "B.Paste" user "Package Geometry/Pastemask Bottom")
		(5 "F.SilkS" user "Ref Des/Silkscreen Top")
		(7 "B.SilkS" user "Ref Des/Silkscreen Bottom")
		(1 "F.Mask" user "Board Geometry/Soldermask Top")
		(3 "B.Mask" user "Board Geometry/Soldermask Bottom")
		(17 "Dwgs.User" user "User.Drawings")
		(19 "Cmts.User" user "User.Comments")
		(21 "Eco1.User" user "User.Eco1")
		(23 "Eco2.User" user "User.Eco2")
		(25 "Edge.Cuts" user "Board Geometry/Outline")
		(27 "Margin" user)
		(31 "F.CrtYd" user "Package Geometry/Place Bound Top")
		(29 "B.CrtYd" user "Package Geometry/Place Bound Bottom")
		(35 "F.Fab" user "Ref Des/Assembly Top")
		(33 "B.Fab" user "Ref Des/Assembly Bottom")
	)
	(footprint ""
		(layer "B.Cu")
		(at 87.48776 -188.918088 90)
		(property "Reference" "R774"
			(at 0 0 90)
			(layer "B.SilkS")
			(hide yes)
			(effects
				(font
					(size 1.27 1.27)
				)
				(justify mirror)
			)
		)
		(property "Value" ""
			(at 0 0 90)
			(layer "B.Fab")
			(effects
				(font
					(size 1.27 1.27)
				)
				(justify mirror)
			)
		)
		(duplicate_pad_numbers_are_jumpers no)
		(fp_line
			(start 0.7874 -0.4064)
			(end -0.7874 -0.4064)
			(stroke
				(width 0.1524)
				(type default)
			)
			(layer "B.SilkS")
		)
		(fp_line
			(start -0.7874 -0.4064)
			(end -0.7874 0.4064)
			(stroke
				(width 0.1524)
				(type default)
			)
			(layer "B.SilkS")
		)
		(fp_line
			(start 0.7874 0.4064)
			(end 0.7874 -0.4064)
			(stroke
				(width 0.1524)
				(type default)
			)
			(layer "B.SilkS")
		)
		(fp_line
			(start -0.7874 0.4064)
			(end 0.7874 0.4064)
			(stroke
				(width 0.1524)
				(type default)
			)
			(layer "B.SilkS")
		)
		(fp_line
			(start 0.67945 -0.305054)
			(end 0.12065 -0.305054)
			(stroke
				(width 0.1)
				(type default)
			)
			(layer "B.Fab")
		)
		(fp_line
			(start 0.12065 -0.305054)
			(end 0.12065 -0.2794)
			(stroke
				(width 0.1)
				(type default)
			)
			(layer "B.Fab")
		)
		(fp_line
			(start -0.12065 -0.3048)
			(end -0.67945 -0.3048)
			(stroke
				(width 0.1)
				(type default)
			)
			(layer "B.Fab")
		)
		(fp_line
			(start -0.67945 -0.3048)
			(end -0.67945 0.3048)
			(stroke
				(width 0.1)
				(type default)
			)
			(layer "B.Fab")
		)
		(fp_line
			(start 0.12065 -0.2794)
			(end -0.12065 -0.2794)
			(stroke
				(width 0.1)
				(type default)
			)
			(layer "B.Fab")
		)
		(fp_line
			(start -0.12065 -0.2794)
			(end -0.12065 -0.3048)
			(stroke
				(width 0.1)
				(type default)
			)
			(layer "B.Fab")
		)
		(fp_line
			(start 0.12065 0.2794)
			(end 0.12065 0.3048)
			(stroke
				(width 0.1)
				(type default)
			)
			(layer "B.Fab")
		)
		(fp_line
			(start -0.120396 0.2794)
			(end 0.12065 0.2794)
			(stroke
				(width 0.1)
				(type default)
			)
			(layer "B.Fab")
		)
		(fp_line
			(start 0.67945 0.3048)
			(end 0.67945 -0.305054)
			(stroke
				(width 0.1)
				(type default)
			)
			(layer "B.Fab")
		)
		(fp_line
			(start 0.12065 0.3048)
			(end 0.67945 0.3048)
			(stroke
				(width 0.1)
				(type default)
			)
			(layer "B.Fab")
		)
		(fp_line
			(start -0.120396 0.3048)
			(end -0.120396 0.2794)
			(stroke
				(width 0.1)
				(type default)
			)
			(layer "B.Fab")
		)
		(fp_line
			(start -0.67945 0.3048)
			(end -0.120396 0.3048)
			(stroke
				(width 0.1)
				(type default)
			)
			(layer "B.Fab")
		)
		(pad "1" smd circle
			(at 0.40005 0 270)
			(size 0 0)
			(layers "B.Cu" "B.Mask" "B.Paste")
			(net "JTAG_DBP_CPU_GTL_TCK")
		)
		(pad "2" smd circle
			(at -0.40005 0 270)
			(size 0 0)
			(layers "B.Cu" "B.Mask" "B.Paste")
			(net "GND")
		)
	)
	(footprint ""
		(layer "B.Cu")
		(at 192.052448 -401.772882 180)
		(property "Reference" "R2587"
			(at 0 0 0)
			(layer "B.SilkS")
			(hide yes)
			(effects
				(font
					(size 1.27 1.27)
				)
				(justify mirror)
			)
		)
		(property "Value" ""
			(at 0 0 0)
			(layer "B.Fab")
			(effects
				(font
					(size 1.27 1.27)
				)
				(justify mirror)
			)
		)
		(duplicate_pad_numbers_are_jumpers no)
		(fp_line
			(start 0.7874 0.4064)
			(end 0.7874 -0.4064)
			(stroke
				(width 0.1524)
				(type default)
			)
			(layer "B.SilkS")
		)
		(fp_line
			(start 0.7874 -0.4064)
			(end -0.7874 -0.4064)
			(stroke
				(width 0.1524)
				(type default)
			)
			(layer "B.SilkS")
		)
		(fp_line
			(start -0.7874 0.4064)
			(end 0.7874 0.4064)
			(stroke
				(width 0.1524)
				(type default)
			)
			(layer "B.SilkS")
		)
		(fp_line
			(start -0.7874 -0.4064)
			(end -0.7874 0.4064)
			(stroke
				(width 0.1524)
				(type default)
			)
			(layer "B.SilkS")
		)
		(fp_line
			(start 0.67945 0.3048)
			(end 0.67945 -0.305054)
			(stroke
				(width 0.1)
				(type default)
			)
			(layer "B.Fab")
		)
		(fp_line
			(start 0.67945 -0.305054)
			(end 0.12065 -0.305054)
			(stroke
				(width 0.1)
				(type default)
			)
			(layer "B.Fab")
		)
		(fp_line
			(start 0.12065 0.3048)
			(end 0.67945 0.3048)
			(stroke
				(width 0.1)
				(type default)
			)
			(layer "B.Fab")
		)
		(fp_line
			(start 0.12065 0.2794)
			(end 0.12065 0.3048)
			(stroke
				(width 0.1)
				(type default)
			)
			(layer "B.Fab")
		)
		(fp_line
			(start 0.12065 -0.2794)
			(end -0.12065 -0.2794)
			(stroke
				(width 0.1)
				(type default)
			)
			(layer "B.Fab")
		)
		(fp_line
			(start 0.12065 -0.305054)
			(end 0.12065 -0.2794)
			(stroke
				(width 0.1)
				(type default)
			)
			(layer "B.Fab")
		)
		(fp_line
			(start -0.120396 0.3048)
			(end -0.120396 0.2794)
			(stroke
				(width 0.1)
				(type default)
			)
			(layer "B.Fab")
		)
		(fp_line
			(start -0.120396 0.2794)
			(end 0.12065 0.2794)
			(stroke
				(width 0.1)
				(type default)
			)
			(layer "B.Fab")
		)
		(fp_line
			(start -0.12065 -0.2794)
			(end -0.12065 -0.3048)
			(stroke
				(width 0.1)
				(type default)
			)
			(layer "B.Fab")
		)
		(fp_line
			(start -0.12065 -0.3048)
			(end -0.67945 -0.3048)
			(stroke
				(width 0.1)
				(type default)
			)
			(layer "B.Fab")
		)
		(fp_line
			(start -0.67945 0.3048)
			(end -0.120396 0.3048)
			(stroke
				(width 0.1)
				(type default)
			)
			(layer "B.Fab")
		)
		(fp_line
			(start -0.67945 -0.3048)
			(end -0.67945 0.3048)
			(stroke
				(width 0.1)
				(type default)
			)
			(layer "B.Fab")
		)
		(pad "1" smd circle
			(at 0.40005 0)
			(size 0 0)
			(layers "B.Cu" "B.Mask" "B.Paste")
			(net "HSC_VDD")
		)
		(pad "2" smd circle
			(at -0.40005 0)
			(size 0 0)
			(layers "B.Cu" "B.Mask" "B.Paste")
			(net "IRQ_HSC_FAULT_N")
		)
	)
	(footprint ""
		(layer "B.Cu")
		(at 282.11272 -193.710814 -90)
		(property "Reference" "R96"
			(at 0 0 90)
			(layer "B.SilkS")
			(hide yes)
			(effects
				(font
					(size 1.27 1.27)
				)
				(justify mirror)
			)
		)
		(property "Value" ""
			(at 0 0 90)
			(layer "B.Fab")
			(effects
				(font
					(size 1.27 1.27)
				)
				(justify mirror)
			)
		)
		(duplicate_pad_numbers_are_jumpers no)
		(fp_line
			(start -0.7874 0.4064)
			(end 0.7874 0.4064)
			(stroke
				(width 0.1524)
				(type default)
			)
			(layer "B.SilkS")
		)
		(fp_line
			(start 0.7874 0.4064)
			(end 0.7874 -0.4064)
			(stroke
				(width 0.1524)
				(type default)
			)
			(layer "B.SilkS")
		)
		(fp_line
			(start -0.7874 -0.4064)
			(end -0.7874 0.4064)
			(stroke
				(width 0.1524)
				(type default)
			)
			(layer "B.SilkS")
		)
		(fp_line
			(start 0.7874 -0.4064)
			(end -0.7874 -0.4064)
			(stroke
				(width 0.1524)
				(type default)
			)
			(layer "B.SilkS")
		)
		(fp_line
			(start -0.67945 0.3048)
			(end -0.120396 0.3048)
			(stroke
				(width 0.1)
				(type default)
			)
			(layer "B.Fab")
		)
		(fp_line
			(start -0.120396 0.3048)
			(end -0.120396 0.2794)
			(stroke
				(width 0.1)
				(type default)
			)
			(layer "B.Fab")
		)
		(fp_line
			(start 0.12065 0.3048)
			(end 0.67945 0.3048)
			(stroke
				(width 0.1)
				(type default)
			)
			(layer "B.Fab")
		)
		(fp_line
			(start 0.67945 0.3048)
			(end 0.67945 -0.305054)
			(stroke
				(width 0.1)
				(type default)
			)
			(layer "B.Fab")
		)
		(fp_line
			(start -0.120396 0.2794)
			(end 0.12065 0.2794)
			(stroke
				(width 0.1)
				(type default)
			)
			(layer "B.Fab")
		)
		(fp_line
			(start 0.12065 0.2794)
			(end 0.12065 0.3048)
			(stroke
				(width 0.1)
				(type default)
			)
			(layer "B.Fab")
		)
		(fp_line
			(start -0.12065 -0.2794)
			(end -0.12065 -0.3048)
			(stroke
				(width 0.1)
				(type default)
			)
			(layer "B.Fab")
		)
		(fp_line
			(start 0.12065 -0.2794)
			(end -0.12065 -0.2794)
			(stroke
				(width 0.1)
				(type default)
			)
			(layer "B.Fab")
		)
		(fp_line
			(start -0.67945 -0.3048)
			(end -0.67945 0.3048)
			(stroke
				(width 0.1)
				(type default)
			)
			(layer "B.Fab")
		)
		(fp_line
			(start -0.12065 -0.3048)
			(end -0.67945 -0.3048)
			(stroke
				(width 0.1)
				(type default)
			)
			(layer "B.Fab")
		)
		(fp_line
			(start 0.12065 -0.305054)
			(end 0.12065 -0.2794)
			(stroke
				(width 0.1)
				(type default)
			)
			(layer "B.Fab")
		)
		(fp_line
			(start 0.67945 -0.305054)
			(end 0.12065 -0.305054)
			(stroke
				(width 0.1)
				(type default)
			)
			(layer "B.Fab")
		)
		(pad "1" smd circle
			(at 0.40005 0 90)
			(size 0 0)
			(layers "B.Cu" "B.Mask" "B.Paste")
			(net "PVNN_TERM_CPU0")
		)
		(pad "2" smd circle
			(at -0.40005 0 90)
			(size 0 0)
			(layers "B.Cu" "B.Mask" "B.Paste")
			(net "PU_CPU0_UPI2_AC_COUPLING")
		)
	)
	(footprint ""
		(layer "B.Cu")
		(at 431.5841 -128.791208 -90)
		(property "Reference" "PR4235"
			(at 0 0 90)
			(layer "B.SilkS")
			(hide yes)
			(effects
				(font
					(size 1.27 1.27)
				)
				(justify mirror)
			)
		)
		(property "Value" ""
			(at 0 0 90)
			(layer "B.Fab")
			(effects
				(font
					(size 1.27 1.27)
				)
				(justify mirror)
			)
		)
		(duplicate_pad_numbers_are_jumpers no)
		(fp_line
			(start -0.7874 0.4064)
			(end 0.7874 0.4064)
			(stroke
				(width 0.1524)
				(type default)
			)
			(layer "B.SilkS")
		)
		(fp_line
			(start 0.7874 0.4064)
			(end 0.7874 -0.4064)
			(stroke
				(width 0.1524)
				(type default)
			)
			(layer "B.SilkS")
		)
		(fp_line
			(start -0.7874 -0.4064)
			(end -0.7874 0.4064)
			(stroke
				(width 0.1524)
				(type default)
			)
			(layer "B.SilkS")
		)
		(fp_line
			(start 0.7874 -0.4064)
			(end -0.7874 -0.4064)
			(stroke
				(width 0.1524)
				(type default)
			)
			(layer "B.SilkS")
		)
		(fp_line
			(start -0.67945 0.3048)
			(end -0.120396 0.3048)
			(stroke
				(width 0.1)
				(type default)
			)
			(layer "B.Fab")
		)
		(fp_line
			(start -0.120396 0.3048)
			(end -0.120396 0.2794)
			(stroke
				(width 0.1)
				(type default)
			)
			(layer "B.Fab")
		)
		(fp_line
			(start 0.12065 0.3048)
			(end 0.67945 0.3048)
			(stroke
				(width 0.1)
				(type default)
			)
			(layer "B.Fab")
		)
		(fp_line
			(start 0.67945 0.3048)
			(end 0.67945 -0.305054)
			(stroke
				(width 0.1)
				(type default)
			)
			(layer "B.Fab")
		)
		(fp_line
			(start -0.120396 0.2794)
			(end 0.12065 0.2794)
			(stroke
				(width 0.1)
				(type default)
			)
			(layer "B.Fab")
		)
		(fp_line
			(start 0.12065 0.2794)
			(end 0.12065 0.3048)
			(stroke
				(width 0.1)
				(type default)
			)
			(layer "B.Fab")
		)
		(fp_line
			(start -0.12065 -0.2794)
			(end -0.12065 -0.3048)
			(stroke
				(width 0.1)
				(type default)
			)
			(layer "B.Fab")
		)
		(fp_line
			(start 0.12065 -0.2794)
			(end -0.12065 -0.2794)
			(stroke
				(width 0.1)
				(type default)
			)
			(layer "B.Fab")
		)
		(fp_line
			(start -0.67945 -0.3048)
			(end -0.67945 0.3048)
			(stroke
				(width 0.1)
				(type default)
			)
			(layer "B.Fab")
		)
		(fp_line
			(start -0.12065 -0.3048)
			(end -0.67945 -0.3048)
			(stroke
				(width 0.1)
				(type default)
			)
			(layer "B.Fab")
		)
		(fp_line
			(start 0.12065 -0.305054)
			(end 0.12065 -0.2794)
			(stroke
				(width 0.1)
				(type default)
			)
			(layer "B.Fab")
		)
		(fp_line
			(start 0.67945 -0.305054)
			(end 0.12065 -0.305054)
			(stroke
				(width 0.1)
				(type default)
			)
			(layer "B.Fab")
		)
		(pad "1" smd circle
			(at 0.40005 0 90)
			(size 0 0)
			(layers "B.Cu" "B.Mask" "B.Paste")
			(net "NC_PVCCD_HV_CPU0_ACSP7")
		)
		(pad "2" smd circle
			(at -0.40005 0 90)
			(size 0 0)
			(layers "B.Cu" "B.Mask" "B.Paste")
			(net "GND")
		)
	)
	(footprint ""
		(layer "B.Cu")
		(at 302.300132 -55.971948 180)
		(property "Reference" "C1231"
			(at 0 0 0)
			(layer "B.SilkS")
			(hide yes)
			(effects
				(font
					(size 1.27 1.27)
				)
				(justify mirror)
			)
		)
		(property "Value" ""
			(at 0 0 0)
			(layer "B.Fab")
			(effects
				(font
					(size 1.27 1.27)
				)
				(justify mirror)
			)
		)
		(duplicate_pad_numbers_are_jumpers no)
		(fp_line
			(start 0.7874 0.4064)
			(end 0.7874 -0.4064)
			(stroke
				(width 0.1524)
				(type default)
			)
			(layer "B.SilkS")
		)
		(fp_line
			(start 0.7874 -0.4064)
			(end -0.7874 -0.4064)
			(stroke
				(width 0.1524)
				(type default)
			)
			(layer "B.SilkS")
		)
		(fp_line
			(start -0.7874 0.4064)
			(end 0.7874 0.4064)
			(stroke
				(width 0.1524)
				(type default)
			)
			(layer "B.SilkS")
		)
		(fp_line
			(start -0.7874 -0.4064)
			(end -0.7874 0.4064)
			(stroke
				(width 0.1524)
				(type default)
			)
			(layer "B.SilkS")
		)
		(fp_line
			(start 0.67945 0.3048)
			(end 0.67945 -0.305054)
			(stroke
				(width 0.1)
				(type default)
			)
			(layer "B.Fab")
		)
		(fp_line
			(start 0.67945 -0.305054)
			(end 0.12065 -0.305054)
			(stroke
				(width 0.1)
				(type default)
			)
			(layer "B.Fab")
		)
		(fp_line
			(start 0.12065 0.3048)
			(end 0.67945 0.3048)
			(stroke
				(width 0.1)
				(type default)
			)
			(layer "B.Fab")
		)
		(fp_line
			(start 0.12065 0.2794)
			(end 0.12065 0.3048)
			(stroke
				(width 0.1)
				(type default)
			)
			(layer "B.Fab")
		)
		(fp_line
			(start 0.12065 -0.2794)
			(end -0.12065 -0.2794)
			(stroke
				(width 0.1)
				(type default)
			)
			(layer "B.Fab")
		)
		(fp_line
			(start 0.12065 -0.305054)
			(end 0.12065 -0.2794)
			(stroke
				(width 0.1)
				(type default)
			)
			(layer "B.Fab")
		)
		(fp_line
			(start -0.120396 0.3048)
			(end -0.120396 0.2794)
			(stroke
				(width 0.1)
				(type default)
			)
			(layer "B.Fab")
		)
		(fp_line
			(start -0.120396 0.2794)
			(end 0.12065 0.2794)
			(stroke
				(width 0.1)
				(type default)
			)
			(layer "B.Fab")
		)
		(fp_line
			(start -0.12065 -0.2794)
			(end -0.12065 -0.3048)
			(stroke
				(width 0.1)
				(type default)
			)
			(layer "B.Fab")
		)
		(fp_line
			(start -0.12065 -0.3048)
			(end -0.67945 -0.3048)
			(stroke
				(width 0.1)
				(type default)
			)
			(layer "B.Fab")
		)
		(fp_line
			(start -0.67945 0.3048)
			(end -0.120396 0.3048)
			(stroke
				(width 0.1)
				(type default)
			)
			(layer "B.Fab")
		)
		(fp_line
			(start -0.67945 -0.3048)
			(end -0.67945 0.3048)
			(stroke
				(width 0.1)
				(type default)
			)
			(layer "B.Fab")
		)
		(pad "1" smd circle
			(at 0.40005 0)
			(size 0 0)
			(layers "B.Cu" "B.Mask" "B.Paste")
			(net "P1V05_PCH_AUX")
		)
		(pad "2" smd circle
			(at -0.40005 0)
			(size 0 0)
			(layers "B.Cu" "B.Mask" "B.Paste")
			(net "GND")
		)
	)
	(footprint ""
		(layer "B.Cu")
		(at 477.81591 -427.280578 180)
		(property "Reference" "DB15"
			(at 2.527554 -8.29691 270)
			(unlocked yes)
			(layer "B.SilkS")
			(effects
				(font
					(size 0.7874 0.5842)
					(thickness 0.1524)
				)
				(justify left mirror)
			)
		)
		(property "Value" ""
			(at 0 0 0)
			(layer "B.Fab")
			(effects
				(font
					(size 1.27 1.27)
				)
				(justify mirror)
			)
		)
		(duplicate_pad_numbers_are_jumpers no)
		(fp_line
			(start 3.330702 -4.771136)
			(end -3.330702 -4.771136)
			(stroke
				(width 0.1524)
				(type default)
			)
			(layer "B.SilkS")
		)
		(fp_line
			(start 0 4.011168)
			(end 3.330702 -4.771136)
			(stroke
				(width 0.1524)
				(type default)
			)
			(layer "B.SilkS")
		)
		(fp_line
			(start -3.330702 -4.771136)
			(end 0 4.011168)
			(stroke
				(width 0.1524)
				(type default)
			)
			(layer "B.SilkS")
		)
		(fp_line
			(start 3.330702 -4.771136)
			(end -3.330702 -4.771136)
			(stroke
				(width 0.1)
				(type default)
			)
			(layer "B.Fab")
		)
		(fp_line
			(start 0 4.011168)
			(end 3.330702 -4.771136)
			(stroke
				(width 0.1)
				(type default)
			)
			(layer "B.Fab")
		)
		(fp_line
			(start -3.330702 -4.771136)
			(end 0 4.011168)
			(stroke
				(width 0.1)
				(type default)
			)
			(layer "B.Fab")
		)
		(pad "1" thru_hole circle
			(at 0 0)
			(size 2.159 2.159)
			(drill 1.7018)
			(layers "*.Cu" "*.Mask")
			(remove_unused_layers no)
			(net "T1_GND")
			(clearance 0.0254)
			(thermal_gap 0.0254)
		)
		(pad "2" thru_hole circle
			(at 1.27 -3.348736)
			(size 2.159 2.159)
			(drill 1.7018)
			(layers "*.Cu" "*.Mask")
			(remove_unused_layers no)
			(net "TDR_SE_50_OHM_IN5")
			(clearance 0.0254)
			(thermal_gap 0.0254)
		)
		(pad "3" thru_hole circle
			(at -1.27 -3.348736)
			(size 2.159 2.159)
			(drill 1.7018)
			(layers "*.Cu" "*.Mask")
			(remove_unused_layers no)
			(net "TDR_SE_50_OHM_IN5")
			(clearance 0.0254)
			(thermal_gap 0.0254)
		)
	)
)
